FILE_TYPE = CONNECTIVITY;
{Allegro Design Entry HDL 17.4-2019 S026 (4007227) 1/17/2022}
"PAGE_NUMBER" = 141;
0"NC";
1"GND\g";
2"GND\g";
3"PVDD18_S5_P0\g";
4"GND\g";
5"P3V3_AUX\g";
6"P5V_AUX\g";
7"GND\g";
8"GND\g";
9"GND\g";
10"GND\g";
11"GND\g";
12"GND\g";
13"UART_LS_EN_N";
14"UART_LS_EN_R_N";
15"UART_CPU0_LVC3_UART0_TX";
16"P3V3_AUX\g";
17"UART_CPU0_UART0_RX";
18"PVDD18_S5_P0\g";
19"UART_CPU0_SCM_LVC3_UART1_TX";
20"UART_CPU0_SCM_UART1_RX";
21"UART_VCC_J13";
22"UART_CPU0_SCM_LVC3_UART1_R_RX";
23"UART_CPU0_LVC3_UART0_RX";
24"UART_CPU0_UART0_TX";
25"UART_CPU0_SCM_UART1_TX";
26"UART_CPU0_SCM_UART1_RX";
27"UART_CPU0_SCM_UART1_R_RX";
28"UART_CPU0_UART0_RX";
29"UART_CPU0_UART0_R_RX";
30"UART_CPU0_SCM_LVC3_UART1_R_TX";
31"UART_CPU0_SCM_LVC3_UART1_TX";
32"UART_CPU0_LVC3_UART0_R_TX";
33"UART_CPU0_LVC3_UART0_TX";
34"UART_CPU0_LVC3_UART0_R_RX";
35"UART_CPU0_LVC3_UART0_RX";
36"PVDD18_S5_P0\g";
37"UART_CPU0_SCM_UART1_TX";
38"UART_CPU0_UART0_TX";
39"PVDD18_S5_P0\g";
40"P3V3_AUX\g";
41"UART_LS_EN_N";
42"UART_CPU0_LVC3_UART0_R_RX";
43"UART_CPU0_SCM_LVC3_UART1_R_RX";
44"UART_CPU0_LVC3_UART0_TX";
45"UART_LS_EN";
%"SN74AVC4T774PWR"
"1","(-4525,3300)","0","pure_quanta","I117";
;
LOCATION"U116"
$SEC"1"
CDS_SEC"1"
VALUE"SN74AVC4T774PWR"
MATERIAL"IC"
PART_TYPE"SMLF"
CDS_LIB"pure_quanta"
NEEDS_NO_SIZE"TRUE"
CDS_LMAN_SYM_OUTLINE"-250,450,250,-450"
PART_NUMBER"AL04T774K00";
"VCCA"
$PN"16"36;
"VCCB"
$PN"15"40;
"B1"
$PN"14"30;
"B2"
$PN"13"43;
"B3"
$PN"12"32;
"B4"
$PN"11"42;
"GND"
$PN"10"9;
"OE \B"
$PN"9"41;
"DIR4"
$PN"8"10;
"DIR3"
$PN"7"39;
"A4"
$PN"6"29;
"A3"
$PN"5"38;
"A2"
$PN"4"27;
"A1"
$PN"3"37;
"DIR2"
$PN"2"11;
"DIR1"
$PN"1"39;
%"UNIVERSAL_POWER"
"1","(-1250,4700)","0","pure_quanta_power","I120";
;
HDL_POWER"P3V3_AUX"
CDS_LIB"pure_quanta_power";
"A"16;
%"UNIVERSAL_POWER"
"1","(-4000,3975)","0","pure_quanta_power","I128";
;
HDL_POWER"P3V3_AUX"
CDS_LIB"pure_quanta_power";
"A"40;
%"Q_CAP"
"1","(-3850,3725)","0","pure_quanta","I133";
;
LOCATION"C1354"
$SEC"1"
CDS_SEC"1"
PACK_TYPE"0402"
MATERIAL"X7R"
TOLERANCE"10%"
VALUE"0.1UF"
VOLTAGE"25V"
CDS_LIB"pure_quanta"
PART_NUMBER"CH4104K1B00";
"B"
$PN"2"1;
"A"
$PN"1"40;
%"UNIVERSAL_GND"
"1","(-3850,3525)","2","pure_quanta_power","I134";
;
CDS_LIB"pure_quanta_power"
HDL_POWER"GND";
"A"1;
%"UNIVERSAL_POWER"
"1","(-5050,3950)","0","pure_quanta_power","I135";
;
HDL_POWER"PVDD18_S5_P0"
CDS_LIB"pure_quanta_power";
"A"36;
%"UNIVERSAL_GND"
"1","(-5175,3525)","0","pure_quanta_power","I136";
;
CDS_LIB"pure_quanta_power"
HDL_POWER"GND";
"A"2;
%"Q_CAP"
"1","(-5175,3725)","2","pure_quanta","I137";
;
LOCATION"C1352"
$SEC"1"
CDS_SEC"1"
VALUE"0.1UF"
PACK_TYPE"0402"
MATERIAL"X7R"
VOLTAGE"25V"
TOLERANCE"10%"
CDS_LIB"pure_quanta"
PART_NUMBER"CH4104K1B00";
"B"
$PN"2"2;
"A"
$PN"1"36;
%"UNIVERSAL_POWER"
"1","(-7425,4425)","0","pure_quanta_power","I145";
;
HDL_POWER"PVDD18_S5_P0"
CDS_LIB"pure_quanta_power";
"A"18;
%"UNIVERSAL_POWER"
"1","(-6875,2750)","0","pure_quanta_power","I148";
;
HDL_POWER"PVDD18_S5_P0"
CDS_LIB"pure_quanta_power";
"A"3;
%"UNIVERSAL_GND"
"1","(-1975,1175)","2","pure_quanta_power","I180";
;
CDS_LIB"pure_quanta_power"
HDL_POWER"GND";
"A"4;
%"UNIVERSAL_POWER"
"1","(-2150,1325)","0","pure_quanta_power","I181";
;
HDL_POWER"P3V3_AUX"
CDS_LIB"pure_quanta_power"
BOM_COST"VR_SYSTEM ";
"A"5;
%"P1V0"
"1","(-2375,1325)","0","pure_quanta_power","I182";
;
HDL_POWER"P5V_AUX"
CDS_LIB"pure_quanta_power";
"A"6;
%"Q_RES"
"2","(-2150,1075)","0","pure_quanta","I185";
;
LOCATION"R821"
$SEC"1"
CDS_SEC"1"
PACK_TYPE"0402LF"
VALUE"10K"
TOLERANCE"5%"
MATERIAL"CHIP"
WATTAGE"1/16W"
CDS_LIB"pure_quanta"
PART_NUMBER"CS31002JB08";
"A"
$PN"1"5;
"B"
$PN"2"21;
%"Q_RES"
"1","(-2375,1100)","1","pure_quanta","I186";
;
LOCATION"R820"
$SEC"1"
CDS_SEC"1"
PACK_TYPE"0402LF"
TOLERANCE"5%"
MATERIAL"EMPTY"
WATTAGE"1/16W"
VALUE"10K"
CDS_LIB"pure_quanta"
PART_NUMBER"CS31002JB08";
"B"
$PN"2"6;
"A"
$PN"1"21;
%"Q_CAP"
"1","(-2575,1150)","0","pure_quanta","I187";
;
LOCATION"C364"
$SEC"1"
CDS_SEC"1"
TOLERANCE"5%"
VOLTAGE"50V"
PACK_TYPE"C0402"
VALUE"220PF"
CDS_LIB"pure_quanta"
MATERIAL"C0G"
PART_NUMBER"CH12206JB00";
"B"
$PN"2"7;
"A"
$PN"1"35;
%"UNIVERSAL_GND"
"1","(-2575,950)","2","pure_quanta_power","I188";
;
CDS_LIB"pure_quanta_power"
HDL_POWER"GND";
"A"7;
%"UNIVERSAL_GND"
"1","(-2775,950)","2","pure_quanta_power","I189";
;
CDS_LIB"pure_quanta_power"
HDL_POWER"GND";
"A"8;
%"Q_CAP"
"1","(-2775,1150)","0","pure_quanta","I190";
;
LOCATION"C363"
$SEC"1"
CDS_SEC"1"
PACK_TYPE"C0402"
TOLERANCE"5%"
VALUE"220PF"
VOLTAGE"50V"
CDS_LIB"pure_quanta"
MATERIAL"C0G"
PART_NUMBER"CH12206JB00";
"B"
$PN"2"8;
"A"
$PN"1"44;
%"CONN4_HFK1040L0P1L7H"
"1","(-1325,1450)","0","pure_quanta","I195";
;
LOCATION"J13"
$SEC"1"
CDS_SEC"1"
PART_TYPE"THLF"
MATERIAL"IO"
VALUE"CONN4_HFK1040-L0P1L-7H"
CDS_LIB"pure_quanta"
CDS_LMAN_SYM_OUTLINE"-75,125,75,-125"
NEEDS_NO_SIZE"TRUE"
PART_NUMBER"DFHD04MS460";
"1"
$PN"1"21;
"2"
$PN"2"35;
"3"
$PN"3"44;
"4"
$PN"4"4;
%"Q_RES"
"2","(-7425,4125)","0","pure_quanta","I196";
;
LOCATION"R816"
$SEC"1"
CDS_SEC"1"
MATERIAL"CHIP"
VALUE"10K"
WATTAGE"1/16W"
PACK_TYPE"0402LF"
TOLERANCE"5%"
CDS_LIB"pure_quanta"
PART_NUMBER"CS31002JB08";
"A"
$PN"1"18;
"B"
$PN"2"20;
%"Q_RES"
"2","(-7625,4125)","0","pure_quanta","I197";
;
LOCATION"R815"
$SEC"1"
CDS_SEC"1"
VALUE"10K"
MATERIAL"EMPTY"
PACK_TYPE"0402LF"
TOLERANCE"5%"
WATTAGE"1/16W"
CDS_LIB"pure_quanta"
PART_NUMBER"CS31002JB08";
"A"
$PN"1"18;
"B"
$PN"2"25;
%"Q_RES"
"2","(-7850,4125)","0","pure_quanta","I198";
;
LOCATION"R814"
$SEC"1"
CDS_SEC"1"
VALUE"10K"
PACK_TYPE"0402LF"
MATERIAL"EMPTY"
WATTAGE"1/16W"
TOLERANCE"5%"
CDS_LIB"pure_quanta"
PART_NUMBER"CS31002JB08";
"A"
$PN"1"18;
"B"
$PN"2"24;
%"Q_RES"
"2","(-8050,4125)","0","pure_quanta","I199";
;
LOCATION"R813"
$SEC"1"
CDS_SEC"1"
MATERIAL"CHIP"
PACK_TYPE"0402LF"
WATTAGE"1/16W"
VALUE"10K"
TOLERANCE"5%"
CDS_LIB"pure_quanta"
PART_NUMBER"CS31002JB08";
"A"
$PN"1"18;
"B"
$PN"2"17;
%"Q_RES"
"2","(-625,4425)","0","pure_quanta","I203";
;
LOCATION"R825"
$SEC"1"
CDS_SEC"1"
VALUE"10K"
PACK_TYPE"0402LF"
MATERIAL"EMPTY"
WATTAGE"1/16W"
TOLERANCE"5%"
CDS_LIB"pure_quanta"
PART_NUMBER"CS31002JB08";
"A"
$PN"1"16;
"B"
$PN"2"23;
%"Q_RES"
"2","(-825,4425)","0","pure_quanta","I204";
;
LOCATION"R824"
$SEC"1"
CDS_SEC"1"
MATERIAL"CHIP"
PACK_TYPE"0402LF"
VALUE"10K"
TOLERANCE"5%"
WATTAGE"1/16W"
CDS_LIB"pure_quanta"
PART_NUMBER"CS31002JB08";
"A"
$PN"1"16;
"B"
$PN"2"15;
%"Q_RES"
"2","(-1050,4425)","0","pure_quanta","I205";
;
LOCATION"R823"
$SEC"1"
CDS_SEC"1"
WATTAGE"1/16W"
TOLERANCE"5%"
MATERIAL"EMPTY"
PACK_TYPE"0402LF"
VALUE"10K"
CDS_LIB"pure_quanta"
PART_NUMBER"CS31002JB08";
"A"
$PN"1"16;
"B"
$PN"2"22;
%"Q_RES"
"2","(-1250,4425)","0","pure_quanta","I206";
;
LOCATION"R822"
$SEC"1"
CDS_SEC"1"
MATERIAL"CHIP"
VALUE"10K"
TOLERANCE"5%"
WATTAGE"1/16W"
PACK_TYPE"0402LF"
CDS_LIB"pure_quanta"
PART_NUMBER"CS31002JB08";
"A"
$PN"1"16;
"B"
$PN"2"19;
%"Q_RES"
"1","(-6250,2325)","2","pure_quanta","I211";
;
LOCATION"R1253"
$SEC"1"
CDS_SEC"1"
VALUE"33"
CDS_LIB"pure_quanta"
BOM_COST"MEM"
WATTAGE"1/16W"
MATERIAL"CHIP"
TOLERANCE"5%"
PACK_TYPE"0402LF"
PART_NUMBER"CS03302JB10";
"B"
$PN"2"14;
"A"
$PN"1"13;
%"Q_RES"
"1","(-2950,1425)","0","pure_quanta","I212";
;
LOCATION"R819"
$SEC"1"
CDS_SEC"1"
VALUE"0"
PACK_TYPE"0402LF"
TOLERANCE"5%"
MATERIAL"CHIP"
WATTAGE"1/16W"
CDS_LIB"pure_quanta"
PART_NUMBER"CS00002JB13";
"B"
$PN"2"35;
"A"
$PN"1"34;
%"Q_RES"
"1","(-3050,3350)","0","pure_quanta","I220";
;
LOCATION"R818"
$SEC"1"
CDS_SEC"1"
VALUE"0"
CDS_LIB"pure_quanta"
WATTAGE"1/16W"
MATERIAL"CHIP"
TOLERANCE"5%"
PACK_TYPE"0402LF"
PART_NUMBER"CS00002JB13";
"B"
$PN"2"33;
"A"
$PN"1"32;
%"Q_RES"
"1","(-3050,3450)","0","pure_quanta","I221";
;
LOCATION"R1425"
$SEC"1"
CDS_SEC"1"
VALUE"0"
CDS_LIB"pure_quanta"
WATTAGE"1/16W"
MATERIAL"CHIP"
TOLERANCE"5%"
PACK_TYPE"0402LF"
PART_NUMBER"CS00002JB13";
"B"
$PN"2"31;
"A"
$PN"1"30;
%"UNIVERSAL_GND"
"1","(-3925,2700)","2","pure_quanta_power","I226";
;
CDS_LIB"pure_quanta_power"
HDL_POWER"GND";
"A"9;
%"Q_RES"
"1","(-5825,3300)","0","pure_quanta","I231";
;
LOCATION"R817"
$SEC"1"
CDS_SEC"1"
VALUE"0"
CDS_LIB"pure_quanta"
WATTAGE"1/16W"
MATERIAL"CHIP"
TOLERANCE"5%"
PACK_TYPE"0402LF"
PART_NUMBER"CS00002JB13";
"B"
$PN"2"29;
"A"
$PN"1"28;
%"Q_RES"
"1","(-5825,3400)","0","pure_quanta","I232";
;
LOCATION"R1423"
$SEC"1"
CDS_SEC"1"
VALUE"0"
CDS_LIB"pure_quanta"
WATTAGE"1/16W"
MATERIAL"CHIP"
TOLERANCE"5%"
PACK_TYPE"0402LF"
PART_NUMBER"CS00002JB13";
"B"
$PN"2"27;
"A"
$PN"1"26;
%"UNIVERSAL_GND"
"1","(-5250,3000)","5","pure_quanta_power","I234";
;
CDS_LIB"pure_quanta_power"
HDL_POWER"GND";
"A"10;
%"UNIVERSAL_GND"
"1","(-5250,3100)","5","pure_quanta_power","I235";
;
CDS_LIB"pure_quanta_power"
HDL_POWER"GND";
"A"11;
%"UNIVERSAL_POWER"
"1","(-6100,3175)","0","pure_quanta_power","I236";
;
HDL_POWER"PVDD18_S5_P0"
CDS_LIB"pure_quanta_power";
"A"39;
%"MOSFET_N_GSD"
"1","(-6900,2025)","0","pure_quanta","I89";
;
LOCATION"Q61"
$SEC"1"
CDS_SEC"1"
MATERIAL"IC"
PART_TYPE"SMLF"
VALUE"NX138BK"
CDS_LIB"pure_quanta"
CDS_LMAN_SYM_OUTLINE"-100,100,100,-100"
NEEDS_NO_SIZE"TRUE"
PART_NUMBER"BAM01380023";
"DRAIN"
$PN"D"14;
"SOURCE"
$PN"S"12;
"GATE"
$PN"G"45;
%"UNIVERSAL_GND"
"1","(-6875,1675)","2","pure_quanta_power","I90";
;
CDS_LIB"pure_quanta_power"
HDL_POWER"GND";
"A"12;
%"Q_RES"
"2","(-6875,2550)","0","pure_quanta","I91";
;
LOCATION"R1419"
$SEC"1"
CDS_SEC"1"
TOLERANCE"5%"
PACK_TYPE"0402LF"
MATERIAL"CHIP"
WATTAGE"1/16W"
VALUE"4.7K"
CDS_LIB"pure_quanta"
PART_NUMBER"CS24702JB10";
"A"
$PN"1"3;
"B"
$PN"2"14;
END.
